# BASEBOARD_FAB2 (Tioga Pass) — schematic netlist excerpt (pin names and nets, part order shuffled) for the footprints in the layout excerpt that follows; sources: Cadence DE-HDL packaged netlist, KiCad conversion of Wiwynn_Tioga_Pass_MB.brd

R1G23  RES  5.36K 1.0% CHIP  pkg 0402  page 223 : A = VR_PVDDQ_GHJ_XADDR1 ; B = GND
R1W17  RES  0.0 5% CHIP  pkg 0402  page 115 : A = USB_PCH_BMC_P4_DN_R ; B = USB_PCH_BMC_P4_DN
R25W142  RES  100.0K 1% CHIP  pkg 0402  page 147 : A = PUMP_TACH1 ; B = GND

(kicad_pcb
	(version 20260206)
	(generator "pcbnew")
	(generator_version "10.0")
	(general
		(thickness 1.6)
		(legacy_teardrops no)
	)
	(paper "A4")
	(title_block
		(title "Wiwynn_Tioga_Pass_MB.brd")
		(comment 1 "Tioga Pass / footprints 1428-1430 of 4770")
	)
	(layers
		(0 "F.Cu" signal "TOP")
		(4 "In1.Cu" signal "L2GND")
		(6 "In2.Cu" signal "L3")
		(8 "In3.Cu" signal "L4GND")
		(10 "In4.Cu" signal "L5")
		(12 "In5.Cu" signal "L6GND")
		(14 "In6.Cu" signal "L7VCC")
		(16 "In7.Cu" signal "L8VCC")
		(18 "In8.Cu" signal "L9GND")
		(20 "In9.Cu" signal "L10")
		(22 "In10.Cu" signal "L11GND")
		(24 "In11.Cu" signal "L12")
		(26 "In12.Cu" signal "L13GND")
		(2 "B.Cu" signal "BOTTOM")
		(9 "F.Adhes" user "F.Adhesive")
		(11 "B.Adhes" user "B.Adhesive")
		(13 "F.Paste" user "Package Geometry/Pastemask Top")
		(15 "B.Paste" user "Package Geometry/Pastemask Bottom")
		(5 "F.SilkS" user "Ref Des/Silkscreen Top")
		(7 "B.SilkS" user "Ref Des/Silkscreen Bottom")
		(1 "F.Mask" user "Board Geometry/Soldermask Top")
		(3 "B.Mask" user "Board Geometry/Soldermask Bottom")
		(17 "Dwgs.User" user "User.Drawings")
		(19 "Cmts.User" user "User.Comments")
		(21 "Eco1.User" user "User.Eco1")
		(23 "Eco2.User" user "User.Eco2")
		(25 "Edge.Cuts" user "Board Geometry/Outline")
		(27 "Margin" user)
		(31 "F.CrtYd" user "Package Geometry/Place Bound Top")
		(29 "B.CrtYd" user "Package Geometry/Place Bound Bottom")
		(35 "F.Fab" user "Ref Des/Assembly Top")
		(33 "B.Fab" user "Ref Des/Assembly Bottom")
	)
	(footprint ""
		(layer "F.Cu")
		(at 8.993378 4.911598 -90)
		(property "Reference" "R1G23"
			(at 0 0 270)
			(layer "F.SilkS")
			(hide yes)
			(effects
				(font
					(size 1.27 1.27)
				)
			)
		)
		(property "Value" ""
			(at 0 0 270)
			(layer "F.Fab")
			(effects
				(font
					(size 1.27 1.27)
				)
			)
		)
		(duplicate_pad_numbers_are_jumpers no)
		(fp_poly
			(pts
				(xy -0.2794 -0.1016) (xy 0.2794 -0.1016) (xy 0.2794 0.9906) (xy -0.2794 0.9906)
			)
			(stroke
				(width 0)
				(type default)
			)
			(fill no)
			(layer "F.CrtYd")
		)
		(fp_line
			(start -0.2794 0.9906)
			(end 0.2794 0.9906)
			(stroke
				(width 0.1)
				(type default)
			)
			(layer "F.Fab")
		)
		(fp_line
			(start 0.2794 0.9906)
			(end 0.2794 -0.1016)
			(stroke
				(width 0.1)
				(type default)
			)
			(layer "F.Fab")
		)
		(fp_line
			(start -0.2794 -0.1016)
			(end -0.2794 0.9906)
			(stroke
				(width 0.1)
				(type default)
			)
			(layer "F.Fab")
		)
		(fp_line
			(start 0.2794 -0.1016)
			(end -0.2794 -0.1016)
			(stroke
				(width 0.1)
				(type default)
			)
			(layer "F.Fab")
		)
		(pad "1" smd rect
			(at 0 0 270)
			(size 0.508 0.508)
			(layers "F.Cu" "F.Mask" "F.Paste")
			(net "VR_PVDDQ_GHJ_XADDR1")
		)
		(pad "2" smd rect
			(at 0 0.889 270)
			(size 0.508 0.508)
			(layers "F.Cu" "F.Mask" "F.Paste")
			(net "GND")
		)
		(zone
			(layer "F.Cu")
			(hatch none 0.5)
			(connect_pads
				(clearance 0)
			)
			(min_thickness 0.25)
			(keepout
				(tracks not_allowed)
				(vias allowed)
				(pads allowed)
				(copperpour not_allowed)
				(footprints allowed)
			)
			(placement
				(enabled no)
				(sheetname "")
			)
			(fill
				(thermal_gap 0.5)
				(thermal_bridge_width 0.5)
				(island_removal_mode 0)
			)
			(polygon
				(pts
					(xy 8.358378 4.657598) (xy 8.358378 5.165598) (xy 8.739378 5.165598) (xy 8.739378 4.657598)
				)
			)
		)
		(zone
			(layer "F.Cu")
			(hatch none 0.5)
			(connect_pads
				(clearance 0)
			)
			(min_thickness 0.25)
			(keepout
				(tracks allowed)
				(vias not_allowed)
				(pads allowed)
				(copperpour not_allowed)
				(footprints allowed)
			)
			(placement
				(enabled no)
				(sheetname "")
			)
			(fill
				(thermal_gap 0.5)
				(thermal_bridge_width 0.5)
				(island_removal_mode 0)
			)
			(polygon
				(pts
					(xy 8.739378 4.657598) (xy 8.739378 5.165598) (xy 8.358378 5.165598) (xy 8.358378 4.657598)
				)
			)
		)
	)
	(footprint ""
		(layer "F.Cu")
		(at 435.5719 -19.755612)
		(property "Reference" "R25W142"
			(at -0.8382 -0.67818 0)
			(unlocked yes)
			(layer "F.SilkS")
			(effects
				(font
					(size 0.4064 0.254)
					(thickness 0.1524)
				)
				(justify left)
			)
		)
		(property "Value" ""
			(at 0 0 0)
			(layer "F.Fab")
			(effects
				(font
					(size 1.27 1.27)
				)
			)
		)
		(duplicate_pad_numbers_are_jumpers no)
		(fp_poly
			(pts
				(xy -0.2794 -0.1016) (xy 0.2794 -0.1016) (xy 0.2794 0.9906) (xy -0.2794 0.9906)
			)
			(stroke
				(width 0)
				(type default)
			)
			(fill no)
			(layer "F.CrtYd")
		)
		(fp_line
			(start -0.2794 -0.1016)
			(end -0.2794 0.9906)
			(stroke
				(width 0.1)
				(type default)
			)
			(layer "F.Fab")
		)
		(fp_line
			(start -0.2794 0.9906)
			(end 0.2794 0.9906)
			(stroke
				(width 0.1)
				(type default)
			)
			(layer "F.Fab")
		)
		(fp_line
			(start 0.2794 -0.1016)
			(end -0.2794 -0.1016)
			(stroke
				(width 0.1)
				(type default)
			)
			(layer "F.Fab")
		)
		(fp_line
			(start 0.2794 0.9906)
			(end 0.2794 -0.1016)
			(stroke
				(width 0.1)
				(type default)
			)
			(layer "F.Fab")
		)
		(pad "1" smd rect
			(at 0 0)
			(size 0.508 0.508)
			(layers "F.Cu" "F.Mask" "F.Paste")
			(net "PUMP_TACH1")
		)
		(pad "2" smd rect
			(at 0 0.889)
			(size 0.508 0.508)
			(layers "F.Cu" "F.Mask" "F.Paste")
			(net "GND")
		)
		(zone
			(layer "F.Cu")
			(hatch none 0.5)
			(connect_pads
				(clearance 0)
			)
			(min_thickness 0.25)
			(keepout
				(tracks allowed)
				(vias not_allowed)
				(pads allowed)
				(copperpour not_allowed)
				(footprints allowed)
			)
			(placement
				(enabled no)
				(sheetname "")
			)
			(fill
				(thermal_gap 0.5)
				(thermal_bridge_width 0.5)
				(island_removal_mode 0)
			)
			(polygon
				(pts
					(xy 435.3179 -19.501612) (xy 435.8259 -19.501612) (xy 435.8259 -19.120612) (xy 435.3179 -19.120612)
				)
			)
		)
		(zone
			(layer "F.Cu")
			(hatch none 0.5)
			(connect_pads
				(clearance 0)
			)
			(min_thickness 0.25)
			(keepout
				(tracks not_allowed)
				(vias allowed)
				(pads allowed)
				(copperpour not_allowed)
				(footprints allowed)
			)
			(placement
				(enabled no)
				(sheetname "")
			)
			(fill
				(thermal_gap 0.5)
				(thermal_bridge_width 0.5)
				(island_removal_mode 0)
			)
			(polygon
				(pts
					(xy 435.3179 -19.120612) (xy 435.8259 -19.120612) (xy 435.8259 -19.501612) (xy 435.3179 -19.501612)
				)
			)
		)
	)
	(footprint ""
		(layer "F.Cu")
		(at 407.749502 -122.823986 90)
		(property "Reference" "R1W17"
			(at -0.8382 -0.67818 90)
			(unlocked yes)
			(layer "F.SilkS")
			(effects
				(font
					(size 0.4064 0.254)
					(thickness 0.1524)
				)
				(justify left)
			)
		)
		(property "Value" ""
			(at 0 0 90)
			(layer "F.Fab")
			(effects
				(font
					(size 1.27 1.27)
				)
			)
		)
		(duplicate_pad_numbers_are_jumpers no)
		(fp_poly
			(pts
				(xy -0.2794 -0.1016) (xy 0.2794 -0.1016) (xy 0.2794 0.9906) (xy -0.2794 0.9906)
			)
			(stroke
				(width 0)
				(type default)
			)
			(fill no)
			(layer "F.CrtYd")
		)
		(fp_line
			(start 0.2794 -0.1016)
			(end -0.2794 -0.1016)
			(stroke
				(width 0.1)
				(type default)
			)
			(layer "F.Fab")
		)
		(fp_line
			(start -0.2794 -0.1016)
			(end -0.2794 0.9906)
			(stroke
				(width 0.1)
				(type default)
			)
			(layer "F.Fab")
		)
		(fp_line
			(start 0.2794 0.9906)
			(end 0.2794 -0.1016)
			(stroke
				(width 0.1)
				(type default)
			)
			(layer "F.Fab")
		)
		(fp_line
			(start -0.2794 0.9906)
			(end 0.2794 0.9906)
			(stroke
				(width 0.1)
				(type default)
			)
			(layer "F.Fab")
		)
		(pad "1" smd rect
			(at 0 0 90)
			(size 0.508 0.508)
			(layers "F.Cu" "F.Mask" "F.Paste")
			(net "USB_PCH_BMC_P4_DN_R")
		)
		(pad "2" smd rect
			(at 0 0.889 90)
			(size 0.508 0.508)
			(layers "F.Cu" "F.Mask" "F.Paste")
			(net "USB_PCH_BMC_P4_DN")
		)
		(zone
			(layer "F.Cu")
			(hatch none 0.5)
			(connect_pads
				(clearance 0)
			)
			(min_thickness 0.25)
			(keepout
				(tracks allowed)
				(vias not_allowed)
				(pads allowed)
				(copperpour not_allowed)
				(footprints allowed)
			)
			(placement
				(enabled no)
				(sheetname "")
			)
			(fill
				(thermal_gap 0.5)
				(thermal_bridge_width 0.5)
				(island_removal_mode 0)
			)
			(polygon
				(pts
					(xy 408.003502 -122.569986) (xy 408.003502 -123.077986) (xy 408.384502 -123.077986) (xy 408.384502 -122.569986)
				)
			)
		)
		(zone
			(layer "F.Cu")
			(hatch none 0.5)
			(connect_pads
				(clearance 0)
			)
			(min_thickness 0.25)
			(keepout
				(tracks not_allowed)
				(vias allowed)
				(pads allowed)
				(copperpour not_allowed)
				(footprints allowed)
			)
			(placement
				(enabled no)
				(sheetname "")
			)
			(fill
				(thermal_gap 0.5)
				(thermal_bridge_width 0.5)
				(island_removal_mode 0)
			)
			(polygon
				(pts
					(xy 408.384502 -122.569986) (xy 408.384502 -123.077986) (xy 408.003502 -123.077986) (xy 408.003502 -122.569986)
				)
			)
		)
	)
)
